# BARRELEYE-G2-SXM2 RISER BOARD-EVT-X00-BOM-X01-20171102_Final.xls.xlsx — PWA BOM (bom)
| FOXCONN TECHNOLOGY GROUP |  |  |  |  |  |  |  |  |  |  |  |  |  |  |  |  |  |  |  |
| BILL OF MATERIAL |  |  |  |  |  |  |  |  |  |  |  |  |  |  |  |  |  |  |  |
| REV OF  BOM | X01 | CUSTOMER |  | <name> |  | CUSTOMER P/N |  | PWA P/N： | PWA DESCRIPTION |  |  |  | PRODUCT CODE |  |  | PWA  REV | X00 | DATE | 43041 |
| Sourcing (Single/Sole/Multi) | Critical Commodity (Y or N) | Component Class (1, 2, other) | Customer PSL (Y or N) | Line Item | Item Number | Foxconn P/N | Customer P/N | Part Description | Manufacturer  Full Name | Manufacturer  Part Number | Qty | RoHS Status | Location | CC Qual Build: | Qual by (Customer / ODM ?) | The Date of Change Part or Add 2nd Source | Configuration Identifier | Customer Comments | ODM Comments |
| Multi |  |  |  | 1 | 1 | 0101FFS00-000-G |  | PCB,Zaius-SXM2 Riser Board EVT,OSP,Red,12L,12.925*6.024,G | GOLD CIRCUIT ELECTRONICS LTD. | 0101FFS00-000-G | 1 | G | PCB |  |  |  |  |  |  |
|  |  |  |  |  | 1 | 0101FFS00-000-G |  | PCB,Zaius-SXM2 Riser Board EVT,OSP,Red,12L,12.925*6.024,G | ZHUHAI FOUNDER PRINTED CIRCUIT BOARD（HK） DEVELOPMENT LIMITED | 0101FFS00-000-G |  | G |  |  |  |  |  |  |  |
| Single | Y | 2 | Y(4) | 2 | 2 | 62110GF00-021-G | - | ECAP,470uF,+/-20%,25V,105C,G,SMD10X10,ESR<=80mOhm | NIPPON CHEMI-CON CORPORATION | EMZA250ADA471MJA0G | 1 | G | CE1 |  |  |  |  |  |  |
| Single | ND | ND | N | 3 | 3 | 62120BC00-022-G | - | SPEA,CAP,560uF,+/-20%,16V,105C,G,SMD8*11.9,ESR<=14mOhm | SANYO ELECTRIC CO., LTD. | 16SVPF560M | 4 | G | CE2,CE6,CE7,CE8 |  |  |  |  |  |  |
| Multi | Y | 2 | Y(3) | 4 | 4 | 62011DF01-015-G | - | CAP,220nF,+/-10%,X7R,16V,G,SMD0402 | MURATA ELEC. NORTH AMERICA | GRM155R71C224K | 64 | G | C1,C2,C3,C4,C5,C6,C415,C416,C418,C419,C420,C421,C422,C423,C424,C425,C426,C427,C428,C429,C430,C431,C432,C433,C434,C435,C436,C437,C438,C439,C440,C2198,C2199,C2200,C2201,C2202,C2203,C2204,C2205,C2206,C2207,C2208,C2209,C2210,C2211,C2212,C2213,C2214,C2215,C2216,C2217,C2218,C2219,C2220,C2221,C2222,C2223,C2224,C2225,C2226,C2227,C2228,C2229,C2237 |  |  |  |  |  |  |
|  |  |  |  |  | 4 | 62011DF00-026-G |  | CAP,220nF,+/-10%,X7R,16V,G,SMD0402 | SAMSUNG SEMICONDUCTOR | CL05B224KO5NNNC |  | G |  |  |  |  |  |  |  |
|  |  |  |  |  | 4 | 62011DF00-023-G |  | CAP,220nF,+/-10%,X7R,16V,G,SMD0402 | TAIYO ELECTRIC IND.CO.LTD | EMK105B7224KV-FR |  | G |  |  |  |  |  |  |  |
| Multi | N | ND | Y(3) | 5 | 5 | 62012GG00-015-G | - | CAP,10uF,+/-10%,X7S,25V,G,SMD0805 | MURATA ELEC. NORTH AMERICA | GRM21BC71E106K | 4 | G | C409,C410,C412,C414 |  |  |  |  |  |  |
|  |  |  |  |  | 5 | 62012GG00-012-G |  | CAP,10uF,+/-10%,X7S,25V,G,SMD0805 | WALSIN TECHNOLOGY CORPORATION | 0805A106K250CT |  | G |  |  |  |  |  |  |  |
| Multi | ND | ND | Y(1) | 6 | 6 | 62012A400-015-G | - | CAP,100nF,+/-10%,X7R,25V,G,SMD0402 | MURATA ELEC. NORTH AMERICA | GRM155R71E104KE14D | 3 | G | PSTC13,C411,C413 |  |  |  |  |  |  |
|  |  |  |  |  | 6 | 62012A400-023-G |  | CAP,100nF,+/-10%,X7R,25V,G,SMD0402 | TAIYO ELECTRIC IND.CO.LTD | TMK105B7104KV-FR |  | G |  |  |  |  |  |  |  |
|  |  |  |  |  | 6 | 62012A400-026-G |  | CAP,100nF,+/-10%,X7R,25V,G,SMD0402 | SAMSUNG SEMICONDUCTOR | CL05B104KA5NNNC |  | G |  |  |  |  |  |  |  |
|  |  |  |  |  | 6 | 62012A400-012-G |  | CAP,100nF,+/-10%,X7R,25V,G,SMD0402 | WALSIN TECHNOLOGY CORPORATION | 0402B104K250CT |  | G |  |  |  |  |  |  |  |
| Multi | N | ND | Y(1) | 7 | 7 | 62012PT00-015-G | - | CAP,22uF,+/-20%,X6S,16V,G,SMD0805 | MURATA ELEC. NORTH AMERICA | GRM21BC81C226M | 28 | G | PSTC14,PSTC15,PSTC16,PSTC17,PSTC18,PSTC19,PSTC23,PSTC24,PSTC25,PSTC26,PSTC27,PSTC28,PSTC29,PSTC30,PSTC31,PSTC32,PSTC33,PSTC34,C1929,C1930,C1991,C1992,C1993,C2231,C2232,C2233,C2234,C2235 |  |  |  |  |  |  |
|  |  |  |  |  | 7 | 62012PT00-023-G |  | CAP,22uF,+/-20%,X6S,16V,G,SMD0805 | TAIYO ELECTRIC IND.CO.LTD | EDK212BC6226MG-T |  | G |  |  |  |  |  |  |  |
| Multi | Y | ND | Y(3) | 8 | 8 | 62011U701-015-G | - | CAP,10nF,+/-10%,X7R,6.3V,G,SMD0402 | MURATA ELEC. NORTH AMERICA | GRM155R70J103K | 2 | G | C2172,C2173 |  |  |  |  |  |  |
|  |  |  |  |  | 8 | 62011U700-012-G |  | CAP,10nF,+/-10%,X7R,6.3V,G,SMD0402 | WALSIN TECHNOLOGY CORPORATION | 0402B103K6R3CT |  | G |  |  |  |  |  |  |  |
|  |  |  |  |  | 8 | 62011U700-023-G |  | CAP,10nF,+/-10%,X7R,6.3V,G,SMD0402 | TAIYO ELECTRIC IND.CO.LTD | JMK105B7103KV-F |  | G |  |  |  |  |  |  |  |
| Multi | Y | ND | Y(3) | 9 | 9 | 62011KG00-015-G | - | CAP,100nF,+/-5%,X7R,10V,G,SMD0402 | MURATA ELEC. NORTH AMERICA | GRM155R71A104JA01D | 25 | G | C2174,C2175,C2176,C2181,C2184,C2185,C2186,C2188,C2189,C2190,C2191,C2192,C2193,C2194,C2195,C2196,C2197,C2230,C2236,C2238,C2239,C2240,C2241,C2244,C2245 |  |  |  |  |  |  |
|  |  |  |  |  | 9 | 62011KG00-012-G |  | CAP,100nF,+/-5%,X7R,10V,G,SMD0402 | WALSIN TECHNOLOGY CORPORATION | 0402B104J100CT |  | G |  |  |  |  |  |  |  |
|  |  |  |  |  | 9 | 62011KG00-026-G |  | CAP,100nF,+/-5%,X7R,10V,G,SMD0402 | SAMSUNG SEMICONDUCTOR | CL05B104JP5NNNC |  | G |  |  |  |  |  |  |  |
| Single | Y | 1 | N | 10 | 10 | 521107T00-289-G | KX549 | LED,Gre,LTST-C190KGKT,2.4V,30mA,G,SMD0603 | LITE-ON TECHNOLOGY CORPORATION | LTST-C190KGKT | 1 | G | LED_GPU_PWR_PG |  |  |  |  |  |  |
| Multi | Y | 2 | Y(3) | 11 | 11 | 620101T02-015-G | - | CAP,100nF,+/-10%,X7R,16V,G,SMD0402 | MURATA ELEC. NORTH AMERICA | GRM155R71C104K | 2 | G | PSTC2,PSTC22 |  |  |  |  |  |  |
|  |  |  |  |  | 11 | 620101T00-012-G |  | CAP,100nF,+/-10%,X7R,16V,G,SMD0402 | WALSIN TECHNOLOGY CORPORATION | 0402B104K160CT |  | G |  |  |  |  |  |  |  |
|  |  |  |  |  | 11 | 620101T00-026-G |  | CAP,100nF,+/-10%,X7R,16V,G,SMD0402 | SAMSUNG SEMICONDUCTOR | CL05B104KO5NNNC |  | G |  |  |  |  |  |  |  |
|  |  |  |  |  | 11 | 620101T00-015-G |  | CAP,100nF,+/-10%,X7R,16V,G,SMD0402 | MURATA ELEC. NORTH AMERICA | GRM155R71C104KA88D |  | G |  |  |  |  |  |  |  |
| Multi | ND | ND | Y(1) | 12 | 12 | 62011F100-015-G |  | CAP,1uF,+/-10%,X7R,25V,G,SMD0603 | MURATA ELEC. NORTH AMERICA | GRM188R71E105K | 1 | G | PSTC3 |  |  |  |  |  |  |
|  |  |  |  |  | 12 | 62011F100-023-G |  | CAP,1uF,+/-10%,X7R,25V,G,SMD0603 | TAIYO ELECTRIC IND.CO.LTD | TMK107B7105KA-T |  | G |  |  |  |  |  |  |  |
|  |  |  |  |  | 12 | 62011F100-026-G |  | CAP,1uF,+/-10%,X7R,25V,G,SMD0603 | SAMSUNG SEMICONDUCTOR | CL10B105KA8NNNC |  | G |  |  |  |  |  |  |  |
| Multi | ND | ND | Y(1) | 13 | 13 | 62012AJ01-015-G | - | CAP,22uF,+/-20%,X5R,25V,G,SMD0805 | MURATA ELEC. NORTH AMERICA | GRM21BR61E226M | 7 | G | PSTC4,PSTC5,PSTC6,PSTC7,PSTC9,PSTC10,PSTC11 |  |  |  |  |  |  |
|  |  |  |  |  | 13 | 62012AJ00-026-G |  | CAP,22uF,+/-20%,X5R,25V,G,SMD0805 | SAMSUNG | CL21A226MAQNNNE |  | G |  |  |  |  |  |  |  |
| Multi | ND | ND | Y(3) | 14 | 14 | 62010JC00-015-G | - | CAP,100nF,+/-10%,X5R,25V,G,SMD0402 | MURATA ELEC. NORTH AMERICA | GRM155R61E104K | 1 | G | PSTC8 |  |  |  |  |  |  |
|  |  |  |  |  | 14 | 62010JC00-023-G |  | CAP,100nF,+/-10%,X5R,25V,G,SMD0402 | TAIYO ELECTRIC IND.CO.LTD | TMK105BJ104KV-F |  | G |  |  |  |  |  |  |  |
|  |  |  |  |  | 14 | 62010JC00-026-G |  | CAP,100nF,+/-10%,X5R,25V,G,SMD0402 | SAMSUNG SEMICONDUCTOR | CL05A104KA5NNNC |  | G |  |  |  |  |  |  |  |
| Multi | Y | 2 | Y(1) | 15 | 15 | 620105400-015-G |  | CAP,1uF,+/-10%,X7R,16V,G,SMD0603 | MURATA ELEC. NORTH AMERICA | GRM188R71C105K | 1 | G | PSTC20 |  |  |  |  |  |  |
|  |  |  |  |  | 15 | 620105400-012-G |  | CAP,1uF,+/-10%,X7R,16V,G,SMD0603 | WALSIN TECHNOLOGY CORPORATION | 0603B105K160CT |  | G |  |  |  |  |  |  | Barreleye 2nd source |
|  |  |  |  |  | 15 | 620105400-011-G |  | CAP,1uF,+/-10%,X7R,16V,G,SMD0603 | YAGEO CORPORATION COMPONENT | CC0603KRX7R7BB105 |  | G |  |  |  |  |  |  | Barreleye 2nd source |
|  |  |  |  |  | 15 | 620105400-026-G |  | CAP,1uF,+/-10%,X7R,16V,G,SMD0603 | SAMSUNG SEMICONDUCTOR | CL10B105KO8NNNC |  | G |  |  |  |  |  |  | Barreleye 2nd source |
|  |  |  |  |  | 15 | 620105400-023-G |  | CAP,1uF,+/-10%,X7R,16V,G,SMD0603 | TAIYO ELECTRIC IND.CO.LTD | EMK107B7105KA-T |  | G |  |  |  |  |  |  | Barreleye 2nd source |
| Multi | ND | ND | N | 16 | 16 | 63033PG00-15A-G | - | IND,22nH@100KHz,+/-15%,22A,249.55uOhm,SHLD,G,SMD | The Inter-Technical Group, Inc. | SLC1615A-R022LHF | 1 | G | PSTL1 |  |  |  |  |  |  |
|  |  |  |  |  | 16 | 63035Y500-129-G |  | IND,22nH@100KHz,+/-15%,22A,249.55uOhm,SHLD,G,SMD | MAG.LAYERS, SCIENTIFIC-TECHNICS (KUNSHAN) CO., LTD. | MSI-400404-22NL-I |  | G |  |  |  |  |  |  |  |
|  |  |  |  |  | 16 | 63035SH00-065-G |  | IND,22nH@100KHz,+/-15%,22A,249.55uOhm,SHLD,G,SMD | DELTA ELECTRONICS INDUSTRIAL CO.,LTD | HCB0439-220 |  | G |  |  |  |  |  |  |  |
| Multi | N |  | N | 17 | 17 | 63032CD00-088-G | - | IND,2.2uH@100KHz,+/-20%,8A,20mOhm,SHLD,G,SMD | COOPER BUSSMANN, INC. | HCM0703-2R2-R | 1 | G | PSTL2 |  |  |  |  |  |  |
|  |  |  |  |  | 17 | 63033JK00-15A-G |  | IND,2.2uH@100KHz,+/-20%,9A,16.5mOhm,SHLD,G,SMD | The Inter-Technical Group, Inc. | SMHC2511A-2R2MHF |  | G |  |  |  |  |  |  |  |
| Multi | N | ND | Y(4) | 18 | 18 | 610107A00-017-G | - | RES,0 Ohm,+/-5%,1/16W,G,SMD0402 | KOA SPEER ELECTRONICS, INC. | RK73Z1ETTP | 49 | G | PSTR1,PSTR2,PSTR7,PSTR9,R1472,R1473,R1482,R1483,R1484,R1485,R1488,R1493,R1494,R1495,R1503,R1511,R1512,R1513,R1525,R1526,R1527,R1531,R1532,R1533,R1535,R1536,R1545,R1554,R1558,R1563,R1564,R1566,R1568,R1572,R1573,R1574,R1575,R1576,R1577,R1578,R1579,R1606,R1608,R1610,R1611,R1612,R1613,R1615,R1616 |  |  |  |  |  |  |
|  |  |  |  |  | 18 | 610107A00-012-G |  | RES,0 Ohm,+/-5%,1/16W,G,SMD0402 | WALSIN TECHNOLOGY CORPORATION | WR04X000PTL |  | G |  |  |  |  |  |  |  |
|  |  |  |  |  | 18 | 610107A00-011-G |  | RES,0 Ohm,+/-5%,1/16W,G,SMD0402 | YAGEO CORPORATION COMPONENT | RC0402JR-070RL |  | G |  |  |  |  |  |  |  |
|  |  |  |  |  | 18 | 610107A00-044-G |  | RES,0 Ohm,+/-5%,1/16W,G,SMD0402 | TA-I TECHNOLOGY CO., LTD | RM04JTN0 |  | G |  |  |  |  |  |  |  |
|  |  |  |  |  | 18 | 610107A00-024-G |  | RES,0 Ohm,+/-5%,1/16W,G,SMD0402 | PANASONIC INDUSTRIAL CO.,LTD. | ERJ2GE0R00X |  | G |  |  |  |  |  |  |  |
|  |  |  |  |  | 18 | 610107A00-029-G |  | RES,0 Ohm,+/-5%,1/16W,G,SMD0402 | VISHAY ENTER TECHNO LOGY.INC | CRCW04020000Z0ED |  | G |  |  |  |  |  |  |  |
| Multi | ND | ND | Y(5) | 19 | 19 | 611003200-017-G |  | RES,10KOhm,+/-0.1%,1/16W,G,SMD0402 | KOA SPEER ELECTRONICS, INC. | RN731ETTP1002B25 | 1 | G | PSTR3 |  |  |  |  |  |  |
|  |  |  |  |  | 19 | 611003200-012-G |  | RES,10KOhm,+/-0.1%,1/16W,G,SMD0402 | WALSIN TECHNOLOGY CORPORATION | WF04U1002BTL |  | G |  |  |  |  |  |  |  |
|  |  |  |  |  | 19 | 611003200-011-G |  | RES,10KOhm,+/-0.1%,1/16W,G,SMD0402 | YAGEO CORPORATION COMPONENT | RT0402BRE0710KL |  | G |  |  |  |  |  |  |  |
|  |  |  |  |  | 19 | 611003200-044-G |  | RES,10KOhm,+/-0.1%,1/16W,G,SMD0402 | TA-I TECHNOLOGY CO., LTD | RB04BTP1002 |  | G |  |  |  |  |  |  |  |
| Multi | ND | ND | Y(5) | 20 | 20 | 611004E00-017-G |  | RES,75KOhm,+/-0.1%,1/16W,G,SMD0402 | KOA SPEER ELECTRONICS, INC. | RN731ETTP7502B25 | 1 | G | PSTR4 |  |  |  |  |  |  |
|  |  |  |  |  | 20 | 611004E03-011-G |  | RES,75KOhm,+/-0.1%,1/16W,G,SMD0402 | YAGEO CORPORATION COMPONENT | RT0402BRD0775KL |  | G |  |  |  |  |  |  |  |
|  |  |  |  |  | 20 | 611004E04-044-G |  | RES,75KOhm,+/-0.1%,1/16W,G,SMD0402 | TA-I TECHNOLOGY CO., LTD | RB04BTP7502 |  | G |  |  |  |  |  |  |  |
| Multi | ND | ND | Y(4) | 21 | 21 | 61011HA00-017-G |  | RES,1 Ohm,+/-1%,1/16W,G,SMD0402 | KOA SPEER ELECTRONICS, INC. | RK73H1ETTP1R00F | 1 | G | PSTR5 |  |  |  |  |  |  |
|  |  |  |  |  | 21 | 61011HA00-012-G |  | RES,1 Ohm,+/-1%,1/16W,G,SMD0402 | WALSIN TECHNOLOGY CORPORATION | WR04W1R00FTL |  | G |  |  |  |  |  |  |  |
|  |  |  |  |  | 21 | 61011HA00-011-G |  | RES,1 Ohm,+/-1%,1/16W,G,SMD0402 | YAGEO CORPORATION COMPONENT | RC0402FR-071RL |  | G |  |  |  |  |  |  |  |
|  |  |  |  |  | 21 | 61011HA00-044-G |  | RES,1 Ohm,+/-1%,1/16W,G,SMD0402 | TA-I TECHNOLOGY CO., LTD | RM04FTN1R00 |  | G |  |  |  |  |  |  |  |
|  |  |  |  |  | 21 | 61011HA00-029-G |  | RES,1 Ohm,+/-1%,1/16W,G,SMD0402 | VISHAY ENTER TECHNO LOGY.INC | CRCW04021R00FNED |  | G |  |  |  |  |  |  |  |
| Multi | ND | ND | Y(4) | 22 | 22 | 610118700-017-G |  | RES,51.1KOhm,+/-1%,1/16W,G,SMD0402 | KOA SPEER ELECTRONICS, INC. | RK73H1ETTP5112F | 2 | G | PSTR6,PSTR36 |  |  |  |  |  |  |
|  |  |  |  |  | 22 | 610118700-012-G |  | RES,51.1KOhm,+/-1%,1/16W,G,SMD0402 | WALSIN TECHNOLOGY CORPORATION | WR04X5112FTL |  | G |  |  |  |  |  |  |  |
|  |  |  |  |  | 22 | 610118700-011-G |  | RES,51.1KOhm,+/-1%,1/16W,G,SMD0402 | YAGEO CORPORATION COMPONENT | RC0402FR-0751K1L |  | G |  |  |  |  |  |  |  |
|  |  |  |  |  | 22 | 610118700-044-G |  | RES,51.1KOhm,+/-1%,1/16W,G,SMD0402 | TA-I TECHNOLOGY CO., LTD | RM04FTN5112 |  | G |  |  |  |  |  |  |  |
| Multi | ND | ND | Y(4) | 23 | 23 | 61011FG00-017-G |  | RES,107KOhm,+/-1%,1/16W,G,SMD0402 | KOA SPEER ELECTRONICS, INC. | RK73H1ETTP1073F | 2 | G | PSTR8,PSTR35 |  |  |  |  |  |  |
|  |  |  |  |  | 23 | 61011FG00-012-G |  | RES,107KOhm,+/-1%,1/16W,G,SMD0402 | WALSIN TECHNOLOGY CORPORATION | WR04X1073FTL |  | G |  |  |  |  |  |  |  |
|  |  |  |  |  | 23 | 61011FG00-011-G |  | RES,107KOhm,+/-1%,1/16W,G,SMD0402 | YAGEO CORPORATION COMPONENT | RC0402FR-07107KL |  | G |  |  |  |  |  |  |  |
|  |  |  |  |  | 23 | 61011FG00-044-G |  | RES,107KOhm,+/-1%,1/16W,G,SMD0402 | TA-I TECHNOLOGY CO., LTD | RM04FTN1073 |  | G |  |  |  |  |  |  |  |
| Multi | ND | ND | Y(4) | 24 | 24 | 610116G00-017-G | - | RES,150KOhm,+/-1%,1/16W,G,SMD0402 | KOA SPEER ELECTRONICS, INC. | RK73H1ETTP1503F | 1 | G | PSTR12 |  |  |  |  |  |  |
|  |  |  |  |  | 24 | 610116G00-012-G |  | RES,150KOhm,+/-1%,1/16W,G,SMD0402 | WALSIN TECHNOLOGY CORPORATION | WR04X1503FTL |  | G |  |  |  |  |  |  |  |
|  |  |  |  |  | 24 | 610116G00-011-G |  | RES,150KOhm,+/-1%,1/16W,G,SMD0402 | YAGEO CORPORATION COMPONENT | RC0402FR-07150KL |  | G |  |  |  |  |  |  |  |
|  |  |  |  |  | 24 | 610116G00-044-G |  | RES,150KOhm,+/-1%,1/16W,G,SMD0402 | TA-I TECHNOLOGY CO., LTD | RM04FTN1503 |  | G |  |  |  |  |  |  |  |
| Multi | N |  | Y(5) | 25 | 25 | 61100LV00-017-G |  | RES,10KOhm,+/-1%,1/16W,G,SMD0402 | KOA SPEER ELECTRONICS, INC. | RN731ETTP1002F50 | 1 | G | PSTR13 |  |  |  |  |  |  |
|  |  |  |  |  | 25 | 61100LV00-012-G |  | RES,10KOhm,+/-1%,1/16W,G,SMD0402 | WALSIN TECHNOLOGY CORPORATION | WF04T1002FTL |  | G |  |  |  |  |  |  |  |
|  |  |  |  |  | 25 | 61100LV00-011-G |  | RES,10KOhm,+/-1%,1/16W,G,SMD0402 | YAGEO CORPORATION COMPONENT | RT0402FRE0710KL |  | G |  |  |  |  |  |  |  |
|  |  |  |  |  | 25 | 61100LV00-044-G |  | RES,10KOhm,+/-1%,1/16W,G,SMD0402 | TA-I TECHNOLOGY CO., LTD | RB04FTS1002 |  | G |  |  |  |  |  |  |  |
| Multi | ND | ND | Y(4) | 26 | 26 | 61011UM00-017-G | - | RES,240KOhm,+/-1%,1/16W,G,SMD0402 | KOA SPEER ELECTRONICS, INC. | RK73H1ETTP2403F | 1 | G | PSTR14 |  |  |  |  |  |  |
|  |  |  |  |  | 26 | 61011UM00-012-G |  | RES,240KOhm,+/-1%,1/16W,G,SMD0402 | WALSIN TECHNOLOGY CORPORATION | WR04X2403FTL |  | G |  |  |  |  |  |  |  |
|  |  |  |  |  | 26 | 61011UM00-011-G |  | RES,240KOhm,+/-1%,1/16W,G,SMD0402 | YAGEO CORPORATION COMPONENT | RC0402FR-07240KL |  | G |  |  |  |  |  |  |  |
|  |  |  |  |  | 26 | 61011UM00-044-G |  | RES,240KOhm,+/-1%,1/16W,G,SMD0402 | TA-I TECHNOLOGY CO., LTD | RM04FTN2403 |  | G |  |  |  |  |  |  |  |
| Multi | N | Other | Y(4) | 27 | 27 | 61011YJ00-017-G |  | RES,71.5KOhm,+/-1%,1/16W,G,SMD0402 | KOA SPEER ELECTRONICS, INC. | RK73H1ETTP7152F | 1 | G | PSTR16 |  |  |  |  |  |  |
|  |  |  |  |  | 27 | 61011YJ00-012-G |  | RES,71.5KOhm,+/-1%,1/16W,G,SMD0402 | WALSIN TECHNOLOGY CORPORATION | WR04X7152FTL |  | G |  |  |  |  |  |  |  |
|  |  |  |  |  | 27 | 61011YJ00-011-G |  | RES,71.5KOhm,+/-1%,1/16W,G,SMD0402 | YAGEO CORPORATION COMPONENT | RC0402FR-0771K5L |  | G |  |  |  |  |  |  |  |
|  |  |  |  |  | 27 | 61011YJ00-044-G |  | RES,71.5KOhm,+/-1%,1/16W,G,SMD0402 | TA-I TECHNOLOGY CO., LTD | RM04FTN7152 |  | G |  |  |  |  |  |  |  |
| Single | Y | ND | Y(1) | 28 | 28 | 320143Y00-183-G | - | IC,Regulator,TPS548A20RVER,ADJ,15A,G,VQFN-28,SMD | TEXAS INSTRUMENTS | TPS548A20RVER | 1 | G | PSTU1 |  |  |  |  |  |  |
| Multi | ND | ND | N | 29 | 29 | 510302R00-185-G |  | MOS N,BSS138,50V,0.22A,6ohm@4.5V,G,SOT23-3,SMD | FAIRCHILD SEMICONDUCTOR CORP | BSS138 | 1 | G | Q1 |  |  |  |  |  |  |
|  |  |  |  |  | 29 | 510309C00-237-G |  | MOS N,BSS138-7-F,50V,0.2A,3.5ohm@10V,G,SOT23-3,SMD | DIODES INCORPORATION | BSS138-7-F |  | G |  |  |  |  |  |  |  |
|  |  |  |  |  | 29 | 510301D00-223-G |  | MOS N,BSS138LT1G,50V,0.2A,3.5ohm@5V,G,SOT23-3,SMD | ON SEMICONDUCTOR CORP | BSS138LT1G |  | G |  |  |  |  |  |  |  |
| Multi | N | ND | Y(4) | 30 | 30 | 61010L300-017-G | - | RES,1KOhm,+/-1%,1/16W,G,SMD0402 | KOA SPEER ELECTRONICS, INC. | RK73H1ETTP1001F | 10 | G | R1,R2,R722,R737,R738,R1518,R1519,R1520,R1521,R1522 |  |  |  |  |  |  |
|  |  |  |  |  | 30 | 61010L300-012-G |  | RES,1KOhm,+/-1%,1/16W,G,SMD0402 | WALSIN TECHNOLOGY CORPORATION | WR04X1001FTL |  | G |  |  |  |  |  |  |  |
|  |  |  |  |  | 30 | 61010L300-011-G |  | RES,1KOhm,+/-1%,1/16W,G,SMD0402 | YAGEO CORPORATION COMPONENT | RC0402FR-071KL |  | G |  |  |  |  |  |  |  |
|  |  |  |  |  | 30 | 61010L300-044-G |  | RES,1KOhm,+/-1%,1/16W,G,SMD0402 | TA-I TECHNOLOGY CO., LTD | RM04FTN1001 |  | G |  |  |  |  |  |  |  |
|  |  |  |  |  | 30 | 61010L300-024-G |  | RES,1KOhm,+/-1%,1/16W,G,SMD0402 | PANASONIC INDUSTRIAL CO.,LTD. | ERJ2RKF1001X |  | G |  |  |  |  |  |  |  |
|  |  |  |  |  | 30 | 61010L300-029-G |  | RES,1KOhm,+/-1%,1/16W,G,SMD0402 | VISHAY ENTER TECHNO LOGY.INC | CRCW04021K00FKED |  | G |  |  |  |  |  |  |  |
| Multi | N | other | Y(4) | 31 | 31 | 610100T00-017-G |  | RES,1KOhm,+/-5%,1/16W,G,SMD0402 | KOA SPEER ELECTRONICS, INC. | RK73B1ETTP102J | 4 | G | R5,R1490,R1597,R1599 |  |  |  |  |  |  |
|  |  |  |  |  | 31 | 610100T00-012-G |  | RES,1KOhm,+/-5%,1/16W,G,SMD0402 | WALSIN TECHNOLOGY CORPORATION | WR04X102JTL |  | G |  |  |  |  |  |  |  |
|  |  |  |  |  | 31 | 610100T00-011-G |  | RES,1KOhm,+/-5%,1/16W,G,SMD0402 | YAGEO CORPORATION COMPONENT | RC0402JR-071KL |  | G |  |  |  |  |  |  |  |
|  |  |  |  |  | 31 | 610100T00-044-G |  | RES,1KOhm,+/-5%,1/16W,G,SMD0402 | TA-I TECHNOLOGY CO., LTD | RM04JTN102 |  | G |  |  |  |  |  |  |  |
|  |  |  |  |  | 31 | 610100T00-024-G |  | RES,1KOhm,+/-5%,1/16W,G,SMD0402 | PANASONIC INDUSTRIAL CO.,LTD. | ERJ2GEJ102X |  | G |  |  |  |  |  |  |  |
| Multi | N | ND | Y(4) | 32 | 32 | 61010FE00-017-G | - | RES,100 Ohm,+/-1%,1/16W,G,SMD0402 | KOA SPEER ELECTRONICS, INC. | RK73H1ETTP1000F | 1 | G | R73 |  |  |  |  |  |  |
|  |  |  |  |  | 32 | 61010FE00-012-G |  | RES,100 Ohm,+/-1%,1/16W,G,SMD0402 | WALSIN TECHNOLOGY CORPORATION | WR04X1000FTL |  | G |  |  |  |  |  |  |  |
|  |  |  |  |  | 32 | 61010FE00-011-G |  | RES,100 Ohm,+/-1%,1/16W,G,SMD0402 | YAGEO CORPORATION COMPONENT | RC0402FR-07100RL |  | G |  |  |  |  |  |  |  |
|  |  |  |  |  | 32 | 61010FE00-044-G |  | RES,100 Ohm,+/-1%,1/16W,G,SMD0402 | TA-I TECHNOLOGY CO., LTD | RM04FTN1000 |  | G |  |  |  |  |  |  |  |
| Multi | N | ND | Y(4) | 33 | 33 | 61010G500-017-G | - | RES,10KOhm,+/-1%,1/16W,G,SMD0402 | KOA SPEER ELECTRONICS, INC. | RK73H1ETTP1002F | 11 | G | R721,R804,R1475,R1476,R1479,R1480,R1523,R1524,R1601,R1602,R1618 |  |  |  |  |  |  |
|  |  |  |  |  | 33 | 61010G500-012-G |  | RES,10KOhm,+/-1%,1/16W,G,SMD0402 | WALSIN TECHNOLOGY CORPORATION | WR04X1002FTL |  | G |  |  |  |  |  |  |  |
|  |  |  |  |  | 33 | 61010G500-011-G |  | RES,10KOhm,+/-1%,1/16W,G,SMD0402 | YAGEO CORPORATION COMPONENT | RC0402FR-0710KL |  | G |  |  |  |  |  |  |  |
|  |  |  |  |  | 33 | 61010G500-044-G |  | RES,10KOhm,+/-1%,1/16W,G,SMD0402 | TA-I TECHNOLOGY CO., LTD | RM04FTN1002 |  | G |  |  |  |  |  |  |  |
|  |  |  |  |  | 33 | 61010G500-029-G |  | RES,10KOhm,+/-1%,1/16W,G,SMD0402 | VISHAY ENTER TECHNO LOGY.INC | CRCW040210K0FKED |  | G |  |  |  |  |  |  |  |
|  |  |  |  |  | 33 | 61010G500-024-G |  | RES,10KOhm,+/-1%,1/16W,G,SMD0402 | PANASONIC INDUSTRIAL CO.,LTD. | ERJ2RKF1002X |  | G |  |  |  |  |  |  |  |
| Multi | N | ND | Y(4) | 34 | 34 | 610107B00-017-G | K9576 | RES,4.7KOhm,+/-5%,1/16W,G,SMD0402 | KOA SPEER ELECTRONICS, INC. | RK73B1ETTP472J | 19 | G | R1153,R1154,R1496,R1497,R1498,R1499,R1500,R1506,R1507,R1508,R1509,R1510,R1514,R1515,R1585,R1600,R1619,R1625,R1626 |  |  |  |  |  |  |
|  |  |  |  |  | 34 | 610107B00-012-G |  | RES,4.7KOhm,+/-5%,1/16W,G,SMD0402 | WALSIN TECHNOLOGY CORPORATION | WR04X472JTL |  | G |  |  |  |  |  |  |  |
|  |  |  |  |  | 34 | 610107B00-011-G |  | RES,4.7KOhm,+/-5%,1/16W,G,SMD0402 | YAGEO CORPORATION COMPONENT | RC0402JR-074K7L |  | G |  |  |  |  |  |  |  |
|  |  |  |  |  | 34 | 610107B00-044-G |  | RES,4.7KOhm,+/-5%,1/16W,G,SMD0402 | TA-I TECHNOLOGY CO., LTD | RM04JTN472 |  | G |  |  |  |  |  |  |  |
|  |  |  |  |  | 34 | 610107B00-024-G |  | RES,4.7KOhm,+/-5%,1/16W,G,SMD0402 | PANASONIC INDUSTRIAL CO.,LTD. | ERJ2GEJ472X |  | G |  |  |  |  |  |  |  |
|  |  |  |  |  | 34 | 610107B00-029-G |  | RES,4.7KOhm,+/-5%,1/16W,G,SMD0402 | VISHAY ENTER TECHNO LOGY.INC | CRCW04024K70JNED |  | G |  |  |  |  |  |  |  |
| Multi |  |  | Y(4) | 35 | 35 | 61010KJ00-017-G |  | RES,3.3KOhm,+/-5%,1/16W,G,SMD0402 | KOA SPEER ELECTRONICS, INC. | RK73B1ETTP332J | 1 | G | R1489 |  |  |  |  |  |  |
|  |  |  |  |  | 35 | 61010KJ00-012-G |  | RES,3.3KOhm,+/-5%,1/16W,G,SMD0402 | WALSIN TECHNOLOGY CORPORATION | WR04X332JTL |  | G |  |  |  |  |  |  |  |
|  |  |  |  |  | 35 | 61010KJ00-011-G |  | RES,3.3KOhm,+/-5%,1/16W,G,SMD0402 | YAGEO CORPORATION COMPONENT | RC0402JR-073K3L |  | G |  |  |  |  |  |  |  |
|  |  |  |  |  | 35 | 61010KJ00-044-G |  | RES,3.3KOhm,+/-5%,1/16W,G,SMD0402 | TA-I TECHNOLOGY CO., LTD | RM04JTN332 |  | G |  |  |  |  |  |  |  |
|  |  |  |  |  | 35 | 61010KJ00-024-G |  | RES,3.3KOhm,+/-5%,1/16W,G,SMD0402 | PANASONIC INDUSTRIAL CO.,LTD. | ERJ2GEJ332X |  | G |  |  |  |  |  |  |  |
| Single | ND |  | Y(1) | 36 | 36 | 32022BB00-183-G |  | IC,Power Controller,TPS3808G30DBVR,G,SOT23-6,SMD | TEXAS INSTRUMENTS | TPS3808G30DBVR | 1 | G | U45 |  |  |  |  |  |  |
| Single | ND | ND | Y(1) | 37 | 37 | 31050AE00-183-G | - | IC,Buffer,SN74LVC2G07DCKR,1.65~5.5V,G,SC70-6,SMD | TEXAS INSTRUMENTS | SN74LVC2G07DCKR | 2 | G | U75,U172 |  |  |  |  |  |  |
| Multi | ND | ND | Y(3) | 38 | 38 | 310500F00-031-G | - | IC,Buffer,74LVC07APW,1.65~5.5V,G,TSSOP-14,SMD | NXP SEMICONDUCTORS | 74LVC07APW | 1 | G | U101 |  |  |  |  |  |  |
|  |  |  |  |  | 38 | 31050LF00-237-G |  | IC,Buffer,74LVC07AT14-13,1.65V~5.5V,G,TSSOP-14,SMD | DIODES INCORPORATION | 74LVC07AT14-13 |  | G |  |  |  |  |  |  |  |
| Single | ND | ND | N | 39 | 39 | 310201K00-185-G |  | IC,Trigger,NC7SZ74K8X,1.65~5.5V,G,US8-8,SMD | FAIRCHILD SEMICONDUCTOR CORP | NC7SZ74K8X | 1 | G | U164 |  |  |  |  |  |  |
| Multi | N | ND | Y(3) | 40 | 40 | 310101400-031-G | - | IC,Gate&Inverter,74LVC1G08GW,1.65~5.5V,G,SOT353-5,SMD | NXP SEMICONDUCTORS | 74LVC1G08GW | 3 | G | U165,U173,U176 |  |  |  |  |  |  |
|  |  |  |  |  | 40 | 310103J00-223-G |  | IC,Gate&Inverter,NL17SZ08DFT2G,1.65~5.5V,G,SOT353-5,SMD | ON SEMICONDUCTOR CORP | NL17SZ08DFT2G |  | G |  |  |  |  |  |  |  |
|  |  |  |  |  | 40 | 31010J400-131-G |  | IC,Gate&Inverter,TC7SZ08FU,1.8~5.5V,G,SSOP-5,SMD | TOSHIBA ELECTRONICS ASIA LTD | TC7SZ08FU |  | G |  |  |  |  |  |  |  |
| Multi | ND | ND | Y(3) | 41 | 41 | 310502800-031-G |  | IC,Buffer,74LVC1G07GW,1.65~5.5V,G,SOT353-5,SMD | NXP SEMICONDUCTORS | 74LVC1G07GW | 5 | G | U166,U167,U174,U175,U177 |  |  |  |  |  |  |
|  |  |  |  |  | 41 | 31050CU00-131-G |  | IC,Buffer,TC7SZ07FU,1.65~5.5V,G,SSOP-5,SMD | TOSHIBA ELECTRONICS ASIA LTD | TC7SZ07FU |  | G |  |  |  |  |  |  |  |
|  |  |  |  |  | 41 | 310502C00-223-G |  | IC,Buffer,NL17SZ07DFT2G,1.65~5.50V,G,SC-88A/SOT-353-5,SMD | ON SEMICONDUCTOR CORP | NL17SZ07DFT2G |  | G |  |  |  |  |  |  |  |
| Multi | ND |  | N | 42 | 42 | 310504B00-031-G |  | IC,Buffer,74LVC1G17GW,1.65~5.5V,G,SOT353-5,SMD | NXP SEMICONDUCTORS | 74LVC1G17GW | 1 | G | U168 |  |  |  |  |  |  |
|  |  |  |  |  | 42 | 310507Q00-223-G |  | Logic IC,Buffer,NL17SZ17DFT2G,1.65V~5.5V,15ns,SC-88A/SOT-353,5P,G | ON SEMICONDUCTOR CORP | NL17SZ17DFT2G |  | G |  |  |  |  |  |  |  |
|  |  |  |  |  | 42 | 31050BH00-131-G |  | IC,Buffer,TC7SZ17FU,1.65~5.5V,G,SSOP-5,SMD | TOSHIBA ELECTRONICS ASIA LTD | TC7SZ17FU |  | G |  |  |  |  |  |  |  |
| Single | N | 1 | Y(1) | 43 | 43 | 311001L00-031-G |  | IC,Translator,PCA9517ADP,0.9~5.5V;2.7~5.5V,G,TSSOP-8,SMD | NXP SEMICONDUCTORS | PCA9517ADP | 2 | G | U170,U171 |  |  |  |  |  |  |
| Single | ND |  | N | 44 | 44 | 34071BS00-245-G |  | CONN,SAS,V/T,0.6mm,30u,G,SMD-74 | AMPHENOL SHANGHAI CORP. | U10-K074-26BT | 2 | G | J_CP1_NVLINK_BOTTOM,J_CP0_NVLINK_BOTTOM |  |  |  |  |  |  |
| Single | ND |  | N | 45 | 45 | 34071BR00-245-G |  | CONN,SAS,V/T,0.6mm,30u,G,SMD-74 | AMPHENOL SHANGHAI CORP. | U10-K074-260T | 2 | G | J_CP1_NVLINK_TOP,J_CP0_NVLINK_TOP |  |  |  |  |  |  |
| Single | ND |  | N | 46 | 46 | 340636800-600-G |  | CONN,Header,Power,2X9,V/T,Whi,4.2mm,G,DIP-18 | FOXCONN TECHNOLOGY CO.,LTD. | HM3509E-HP1 | 1 | G | J_GPU_PWR |  |  |  |  |  |  |
| Single | ND |  | N | 47 | 47 | 34131VV00-G78-G |  | CONN,BTB,1.27mm,30u,G,SMD-400 | FCI CONNECTORS HONGKONG LTD. | 84740-102LF | 4 | G | J_PEX_GPU1,J_NVLINK_GPU1,J_PEX_GPU0,J_NVLINK_GPU0 |  |  |  |  |  |  |
| Single | Y | 1 | N | 48 | 48 | 340303U00-600-G | 6Y810 | CONN,Slot,PCIE-16X,V/T,Bla,1mm,15u,G,DIP-164 | FOXCONN TECHNOLOGY CO.,LTD. | 2EG0821V-22D | 2 | G | J_PCIE3,J_PCIE4 |  |  |  |  |  |  |
| Single | ND |  | N | 49 | 49 | 340653G00-317-G |  | CONN,Header,Shrouded,2X11,V/T,Bla,2mm,30u,G,SMD-22 | MOLEX INCORPORATED | 87832-6023 | 1 | G | J_SIDEBAND |  |  |  |  |  |  |
| Single | ND |  | N | 50 | 50 | 3406A9J00-309-G |  | CONN,Header,Shrouded,2X5,V/T,Bla,1.27mm,30u,G,SMD-10 | SAMTEC INC. | ASP-193835-01 | 2 | G | J16,J17 |  |  |  |  |  |  |
| Single | ND |  | N | 51 | 51 | 630366300-57M-G |  | IND,100nH@100KHz,+/-10%,51A,0.29mOhm,SHLD,G,SMD | COOPER BUSSMANN, INC. | FP0906R1-R10-R | 2 | G | L9,L10 |  |  |  |  |  |  |
| Multi | ND |  | N | 52 | 52 | 340805A00-638-G |  | CONN,Switch,tact,50mA,12V,G,SMD-2 | E-SWITCH | TL1015AF160QG | 1 | G | SW1 |  |  |  |  |  |  |
|  |  |  |  |  | 52 | 340812T00-653-G |  | CONN,Switch,tact,50mA,12V,Bla,G,SMD-2 | DIPTRONICS MANUFACTURING INC. | MPTLP2-V-T/R |  | G |  |  |  |  |  |  |  |
| Single | ND |  | N | 53 | 53 | 34081AL00-653-G |  | CONN,Switch,slide,Whi,100mA,50V,G,SMD-8 | DIPTRONICS MANUFACTURING INC. | EM-04-Q-T/R | 1 | G | SW2 |  |  |  |  |  |  |
| Single | ND | ND | N | 54 | 54 | 34080C200-653-G | - | CONN,Switch,slide,25mA,24V,Whi,G,SMD-4 | DIPTRONICS MANUFACTURING INC. | DHNF-02-T-V-T/R | 1 | G | SW3 |  |  |  |  |  |  |
